# S9S_MB_2U (Grand Teton) — schematic parts with pin connectivity, parts 2810–2952 of 6093; source: Cadence DE-HDL packaged netlist (pstxprt.dat, pstxnet.dat, pstchip.dat)

PR1333  Q_RES  0 5% CHIP  pkg 0402LF  page 290 : 1 = PVCCFA_EHV_FIVRA_CPU1_VOS3 ; 2 = PVCCFA_EHV_FIVRA_CPU1
PR1334  Q_RES  0 5% CHIP  pkg 0402LF  page 290 : 1 = PVCCFA_EHV_FIVRA_CPU1_VOS4 ; 2 = PVCCFA_EHV_FIVRA_CPU1
PR1335  Q_RES  0 5% CHIP  pkg 0402LF  page 281 : 1 = P3V3_AUX ; 2 = PVPP_HBM_CPU0_VCC
PR1336  Q_RES  9.76K 1% CHIP  pkg 0402LF  page 281 : 1 = PVPP_HBM_CPU0_CS ; 2 = GND
PR1337  Q_RES  38.3K 0.1% CHIP  pkg 0402LF  page 281 : 1 = PVPP_HBM_CPU0_FB ; 2 = SH_PVPP_HBM_CPU0_P
PR1338  Q_RES  0 5% CHIP  pkg 0402LF  page 299 : 1 = P3V3_AUX ; 2 = PVPP_HBM_CPU1_VCC
PR1339  Q_RES  9.76K 1% CHIP  pkg 0402LF  page 299 : 1 = PVPP_HBM_CPU1_CS ; 2 = GND
PR1340  Q_RES  38.3K 0.1% CHIP  pkg 0402LF  page 299 : 1 = PVPP_HBM_CPU1_FB ; 2 = SH_PVPP_HBM_CPU1_P
PR1380  Q_RES  49.9 1% CHIP  pkg 0402LF  page 278 : 1 = P12V_AUX_CPU0_DIMM_ISEN_P ; 2 = PVCCD_HV_CPU0_ISENSE_P
PR1390  Q_RES  49.9 1% CHIP  pkg 0402LF  page 278 : 1 = P12V_AUX_CPU0_DIMM_ISEN_N ; 2 = PVCCD_HV_CPU0_ISENSE_N
PR1400  Q_RES  49.9 1% CHIP  pkg 0402LF  page 296 : 1 = P12V_AUX_CPU1_DIMM_ISEN_P ; 2 = PVCCD_HV_CPU1_ISENSE_P
PR1410  Q_RES  49.9 1% CHIP  pkg 0402LF  page 296 : 1 = P12V_AUX_CPU1_DIMM_ISEN_N ; 2 = PVCCD_HV_CPU1_ISENSE_N
PR1647  Q_RES  10K 1% EMPTY  pkg 0402LF  page 262 : 1 = P3V3_AUX ; 2 = FM_P1V05_PCH_AUX_R_EN
PR1649  Q_RES  2K 1% CHIP  pkg 0402LF  page 262 : 1 = FM_P1V05_PCH_AUX_R_EN ; 2 = GND
PR1653  Q_RES  470 1% CHIP  pkg 0402LF  page 263 : 1 = P1V8_PCH_AUX ; 2 = GND
PR1707  Q_RES  8.87K 1% EMPTY  pkg 0402LF  page 275 : 1 = PVCCINFAON_CPU0_LSET2 ; 2 = GND
PR1708  Q_RES  8.87K 1% EMPTY  pkg 0402LF  page 275 : 1 = PVCCINFAON_CPU0_LSET1 ; 2 = GND
PR1709  Q_RES  8.87K 1% EMPTY  pkg 0402LF  page 276 : 1 = PVCCFA_EHV_CPU0_LSET1 ; 2 = GND
PR1726  Q_RES  8.87K 1% EMPTY  pkg 0402LF  page 293 : 1 = PVCCINFAON_CPU1_LSET1 ; 2 = GND
PR1727  Q_RES  8.87K 1% EMPTY  pkg 0402LF  page 293 : 1 = PVCCINFAON_CPU1_LSET2 ; 2 = GND
PR1728  Q_RES  8.87K 1% EMPTY  pkg 0402LF  page 294 : 1 = PVCCFA_EHV_CPU1_LSET1 ; 2 = GND
PR1746  Q_RES  8.87K 1% EMPTY  pkg 0402LF  page 297 : 1 = PVCCD_HV_CPU1_LSET1 ; 2 = GND
PR1766  Q_RES  3.3 1% CHIP  pkg 0402LF  page 285 : 1 = SW_PVCCIN_CPU1_BOOT2 ; 2 = SW_PVCCIN_CPU1_BOOT2_R
PR1767  Q_RES  3.3 1% CHIP  pkg 0402LF  page 285 : 1 = SW_PVCCIN_CPU1_BOOT1 ; 2 = SW_PVCCIN_CPU1_BOOT1_R
PR1768  Q_RES  3.3 1% CHIP  pkg 0402LF  page 268 : 1 = SW_PVCCIN_CPU0_BOOT4 ; 2 = SW_PVCCIN_CPU0_BOOT4_R
PR1769  Q_RES  3.3 1% CHIP  pkg 0402LF  page 268 : 1 = SW_PVCCIN_CPU0_BOOT3 ; 2 = SW_PVCCIN_CPU0_BOOT3_R
PR1770  Q_RES  3.3 1% CHIP  pkg 0402LF  page 269 : 1 = SW_PVCCIN_CPU0_BOOT6 ; 2 = SW_PVCCIN_CPU0_BOOT6_R
PR1771  Q_RES  3.3 1% CHIP  pkg 0402LF  page 269 : 1 = SW_PVCCIN_CPU0_BOOT5 ; 2 = SW_PVCCIN_CPU0_BOOT5_R
PR1772  Q_RES  3.3 1% CHIP  pkg 0402LF  page 270 : 1 = SW_PVCCIN_CPU0_BOOT8 ; 2 = SW_PVCCIN_CPU0_BOOT8_R
PR1773  Q_RES  3.3 1% CHIP  pkg 0402LF  page 270 : 1 = SW_PVCCIN_CPU0_BOOT7 ; 2 = SW_PVCCIN_CPU0_BOOT7_R
PR1774  Q_RES  3.3 1% CHIP  pkg 0402LF  page 275 : 1 = SW_PVCCINFAON_CPU0_BOOT1 ; 2 = SW_PVCCINFAON_CPU0_BOOT1_R
PR1775  Q_RES  3.3 1% CHIP  pkg 0402LF  page 275 : 1 = SW_PVCCINFAON_CPU0_BOOT2 ; 2 = SW_PVCCINFAON_CPU0_BOOT2_R
PR1776  Q_RES  0 5% CHIP  pkg 0402LF  page 275 : 1 = PVCCINFAON_CPU0_VOS1 ; 2 = PVCCINFAON_CPU0
PR1777  Q_RES  0 5% CHIP  pkg 0402LF  page 275 : 1 = PVCCINFAON_CPU0_VOS2 ; 2 = PVCCINFAON_CPU0
PR1778  Q_RES  3.3 1% CHIP  pkg 0402LF  page 276 : 1 = SW_PVCCFA_EHV_CPU0_BOOT1 ; 2 = SW_PVCCFA_EHV_CPU0_BOOT1_R
PR1779  Q_RES  0 5% CHIP  pkg 0402LF  page 276 : 1 = PVCCFA_EHV_CPU0_NC1 ; 2 = PVCCFA_EHV_CPU0_VDD1
PR1780  Q_RES  3.3 1% CHIP  pkg 0402LF  page 271 : 1 = SW_PVCCFA_EHV_FIVRA_CPU0_BOOT1 ; 2 = SW_PVCCFA_EHV_FIVRA_CPU0_BOOT1_
PR1781  Q_RES  3.3 1% CHIP  pkg 0402LF  page 271 : 1 = SW_PVCCFA_EHV_FIVRA_CPU0_BOOT2 ; 2 = SW_PVCCFA_EHV_FIVRA_CPU0_BOOT2_
PR1782  Q_RES  3.3 1% CHIP  pkg 0402LF  page 272 : 1 = SW_PVCCFA_EHV_FIVRA_CPU0_BOOT3 ; 2 = SW_PVCCFA_EHV_FIVRA_CPU0_BOOT3_
PR1783  Q_RES  3.3 1% CHIP  pkg 0402LF  page 272 : 1 = SW_PVCCFA_EHV_FIVRA_CPU0_BOOT4 ; 2 = SW_PVCCFA_EHV_FIVRA_CPU0_BOOT4_
PR1784  Q_RES  3.3 1% CHIP  pkg 0402LF  page 279 : 1 = SW_PVCCD_HV_CPU0_BOOT1 ; 2 = SW_PVCCD_HV_CPU0_BOOT1_R
PR1785  Q_RES  0 5% CHIP  pkg 0402LF  page 279 : 1 = PVCCD_HV_CPU0_VOS ; 2 = PVCCD_HV_CPU0
PR1786  Q_RES  3.3 1% CHIP  pkg 0402LF  page 267 : 1 = SW_PVCCIN_CPU0_BOOT2 ; 2 = SW_PVCCIN_CPU0_BOOT2_R
PR1787  Q_RES  3.3 1% CHIP  pkg 0402LF  page 267 : 1 = SW_PVCCIN_CPU0_BOOT1 ; 2 = SW_PVCCIN_CPU0_BOOT1_R
PR1788  Q_RES  3.3 1% CHIP  pkg 0402LF  page 286 : 1 = SW_PVCCIN_CPU1_BOOT4 ; 2 = SW_PVCCIN_CPU1_BOOT4_R
PR1789  Q_RES  3.3 1% CHIP  pkg 0402LF  page 286 : 1 = SW_PVCCIN_CPU1_BOOT3 ; 2 = SW_PVCCIN_CPU1_BOOT3_R
PR1790  Q_RES  3.3 1% CHIP  pkg 0402LF  page 287 : 1 = SW_PVCCIN_CPU1_BOOT6 ; 2 = SW_PVCCIN_CPU1_BOOT6_R
PR1791  Q_RES  3.3 1% CHIP  pkg 0402LF  page 287 : 1 = SW_PVCCIN_CPU1_BOOT5 ; 2 = SW_PVCCIN_CPU1_BOOT5_R
PR1792  Q_RES  3.3 1% CHIP  pkg 0402LF  page 288 : 1 = SW_PVCCIN_CPU1_BOOT8 ; 2 = SW_PVCCIN_CPU1_BOOT8_R
PR1793  Q_RES  3.3 1% CHIP  pkg 0402LF  page 288 : 1 = SW_PVCCIN_CPU1_BOOT7 ; 2 = SW_PVCCIN_CPU1_BOOT7_R
PR1794  Q_RES  3.3 1% CHIP  pkg 0402LF  page 293 : 1 = SW_PVCCINFAON_CPU1_BOOT1 ; 2 = SW_PVCCINFAON_CPU1_BOOT1_R
PR1795  Q_RES  3.3 1% CHIP  pkg 0402LF  page 293 : 1 = SW_PVCCINFAON_CPU1_BOOT2 ; 2 = SW_PVCCINFAON_CPU1_BOOT2_R
PR1796  Q_RES  0 5% CHIP  pkg 0402LF  page 293 : 1 = PVCCINFAON_CPU1_VOS1 ; 2 = PVCCINFAON_CPU1
PR1797  Q_RES  0 5% CHIP  pkg 0402LF  page 293 : 1 = PVCCINFAON_CPU1_VOS2 ; 2 = PVCCINFAON_CPU1
PR1798  Q_RES  3.3 1% CHIP  pkg 0402LF  page 294 : 1 = SW_PVCCFA_EHV_CPU1_BOOT1 ; 2 = SW_PVCCFA_EHV_CPU1_BOOT1_R
PR1799  Q_RES  0 5% CHIP  pkg 0402LF  page 294 : 1 = PVCCFA_EHV_CPU1_NC1 ; 2 = PVCCFA_EHV_CPU1_VDD1
PR1800  Q_RES  3.3 1% CHIP  pkg 0402LF  page 289 : 1 = SW_PVCCFA_EHV_FIVRA_CPU1_BOOT1 ; 2 = SW_PVCCFA_EHV_FIVRA_CPU1_BOOT1_
PR1801  Q_RES  3.3 1% CHIP  pkg 0402LF  page 289 : 1 = SW_PVCCFA_EHV_FIVRA_CPU1_BOOT2 ; 2 = SW_PVCCFA_EHV_FIVRA_CPU1_BOOT2_
PR1802  Q_RES  3.3 1% CHIP  pkg 0402LF  page 290 : 1 = SW_PVCCFA_EHV_FIVRA_CPU1_BOOT3 ; 2 = SW_PVCCFA_EHV_FIVRA_CPU1_BOOT3_
PR1803  Q_RES  3.3 1% CHIP  pkg 0402LF  page 290 : 1 = SW_PVCCFA_EHV_FIVRA_CPU1_BOOT4 ; 2 = SW_PVCCFA_EHV_FIVRA_CPU1_BOOT4_
PR1804  Q_RES  3.3 1% CHIP  pkg 0402LF  page 297 : 1 = SW_PVCCD_HV_CPU1_BOOT1 ; 2 = SW_PVCCD_HV_CPU1_BOOT1_R
PR1805  Q_RES  0 5% CHIP  pkg 0402LF  page 297 : 1 = PVCCD_HV_CPU1_VOS ; 2 = PVCCD_HV_CPU1
PR1850  Q_RES  1K 1% EMPTY  pkg 0402LF  page 263 : 1 = GND ; 2 = FM_PCH_P1V8_AUX_EN_R
PR2106  Q_RES  10K 1% CHIP  pkg 0402LF  page 301 : 1 = HSC_VDD ; 2 = HSC_VIN_UVW_N
PR2149  Q_RES  0 5% CHIP  pkg 0402LF  page 301 : 1 = HSC_VDD_R ; 2 = HSC_VDD
PR2220  Q_RES  60.4K 1% CHIP  pkg 0402LF  page 300 : 1 = PVNN_MAIN_CPU1_MODE ; 2 = GND
PR2222  Q_RES  34.8K 1% CHIP  pkg 0402LF  page 300 : 1 = PVNN_MAIN_CPU1_CS ; 2 = GND
PR2336  Q_RES  26.1K 0.1% EMPTY  pkg 0402LF  page 281 : 1 = PVPP_HBM_CPU0_FB ; 2 = FM_HBM_VPP_SEL_CPU0_D
PR2381  Q_RES  26.1K 0.1% EMPTY  pkg 0402LF  page 299 : 1 = PVPP_HBM_CPU1_FB ; 2 = FM_HBM_VPP_SEL_CPU1_D
PR2510  Q_RES  1 1% EMPTY  pkg 0402LF  page 304 : 1 = P12V_HSC_ADC_P ; 2 = P12V_HSC_SENSE2_R1_P
PR2511  Q_RES  1 1% EMPTY  pkg 0402LF  page 304 : 1 = P12V_HSC_ADC_P ; 2 = P12V_HSC_SENSE2_R2_P
PR2512  Q_RES  1 1% EMPTY  pkg 0402LF  page 304 : 1 = P12V_HSC_ADC_P ; 2 = P12V_HSC_SENSE2_R3_P
PR2513  Q_RES  1 1% EMPTY  pkg 0402LF  page 304 : 1 = P12V_HSC_ADC_P ; 2 = P12V_HSC_SENSE2_R4_P
PR2514  Q_RES  10 1% EMPTY  pkg 0402LF  page 304 : 1 = P12V_HSC_ADC_P ; 2 = P12V_HSC_SENSE1_P
PR2515  Q_RES  10 1% EMPTY  pkg 0402LF  page 304 : 1 = P12V_HSC_ADC_N ; 2 = P12V_HSC_SENSE2_R1_N
PR2516  Q_RES  10 1% EMPTY  pkg 0402LF  page 304 : 1 = P12V_HSC_ADC_N ; 2 = P12V_HSC_SENSE2_R2_N
PR2517  Q_RES  10 1% EMPTY  pkg 0402LF  page 304 : 1 = P12V_HSC_ADC_N ; 2 = P12V_HSC_SENSE2_R3_N
PR2518  Q_RES  10 1% EMPTY  pkg 0402LF  page 304 : 1 = P12V_HSC_ADC_N ; 2 = P12V_HSC_SENSE2_R4_N
PR2519  Q_RES  100 1% EMPTY  pkg 0402LF  page 304 : 1 = P12V_HSC_ADC_N ; 2 = P12V_HSC_SENSE1_N
PR2520  Q_RES  1 1% EMPTY  pkg 0402LF  page 304 : 1 = P12V_HSC_SENSE2_P ; 2 = P12V_HSC_SENSE2_R1_P
PR2521  Q_RES  1 1% EMPTY  pkg 0402LF  page 304 : 1 = P12V_HSC_SENSE2_P ; 2 = P12V_HSC_SENSE2_R2_P
PR2522  Q_RES  1 1% EMPTY  pkg 0402LF  page 304 : 1 = P12V_HSC_SENSE2_P ; 2 = P12V_HSC_SENSE2_R3_P
PR2523  Q_RES  1 1% EMPTY  pkg 0402LF  page 304 : 1 = P12V_HSC_SENSE2_P ; 2 = P12V_HSC_SENSE2_R4_P
PR2524  Q_RES  10 1% EMPTY  pkg 0402LF  page 304 : 1 = P12V_HSC_SENSE2_N ; 2 = P12V_HSC_SENSE2_R1_N
PR2525  Q_RES  10 1% EMPTY  pkg 0402LF  page 304 : 1 = P12V_HSC_SENSE2_N ; 2 = P12V_HSC_SENSE2_R2_N
PR2526  Q_RES  10 1% EMPTY  pkg 0402LF  page 304 : 1 = P12V_HSC_SENSE2_N ; 2 = P12V_HSC_SENSE2_R3_N
PR2527  Q_RES  10 1% EMPTY  pkg 0402LF  page 304 : 1 = P12V_HSC_SENSE2_N ; 2 = P12V_HSC_SENSE2_R4_N
PR2528  Q_RES  10 1% EMPTY  pkg 0402LF  page 304 : 1 = P12V_HSC_GATE_G1 ; 2 = P12V_HSC_GATE2
PR2529  Q_RES  10 1% EMPTY  pkg 0402LF  page 304 : 1 = P12V_HSC_GATE_G2 ; 2 = P12V_HSC_GATE2
PR2530  Q_RES  10 1% EMPTY  pkg 0402LF  page 304 : 1 = P12V_HSC_GATE_G3 ; 2 = P12V_HSC_GATE2
PR2531  Q_RES  10 1% EMPTY  pkg 0402LF  page 304 : 1 = P12V_HSC_GATE_G4 ; 2 = P12V_HSC_GATE2

PR2532  Q_SP_RES4P  0.0003 1% EMPTY  pkg R2725_4P  page 304
  1A  \1a\  BI  = P12V_PSU
  1B  \1b\  BI  = P12V_HSC_SENSE2_R2_P
  2A  \2a\  BI  = P12V_MAIN_R
  2B  \2b\  BI  = P12V_HSC_SENSE2_R2_N

PR2533  Q_SP_RES4P  0.0003 1% EMPTY  pkg R2725_4P  page 304
  1A  \1a\  BI  = P12V_PSU
  1B  \1b\  BI  = P12V_HSC_SENSE2_R3_P
  2A  \2a\  BI  = P12V_MAIN_R
  2B  \2b\  BI  = P12V_HSC_SENSE2_R3_N

PR2534  Q_SP_RES4P  0.0003 1% EMPTY  pkg R2725_4P  page 304
  1A  \1a\  BI  = P12V_PSU
  1B  \1b\  BI  = P12V_HSC_SENSE2_R4_P
  2A  \2a\  BI  = P12V_MAIN_R
  2B  \2b\  BI  = P12V_HSC_SENSE2_R4_N

PR2535  Q_RES  10 1% EMPTY  pkg 0402LF  page 304 : 1 = P12V_HSC_GATE_G5 ; 2 = P12V_HSC_GATE2
PR2536  Q_RES  10 1% EMPTY  pkg 0402LF  page 304 : 1 = P12V_HSC_GATE_G6 ; 2 = P12V_HSC_GATE2
PR2537  Q_RES  10 1% EMPTY  pkg 0402LF  page 304 : 1 = P12V_AUX ; 2 = P12V_HSC_GATE_RC
PR2538  Q_RES  10 1% EMPTY  pkg 0402LF  page 304 : 1 = MB0_CM_GATE_G0 ; 2 = P12V_HSC_GATE1
PR2554  Q_RES  0.03 0.1% EMPTY  pkg 2512LF  page 267 : 1 = P12V_AUX ; 2 = SW_P12V_PVCCIN_CPU0_FLT
PR2556  Q_RES  0.03 0.1% EMPTY  pkg 2512LF  page 285 : 1 = P12V_AUX ; 2 = SW_P12V_PVCCIN_CPU1_FLT
PR2718  Q_RES  8.87K 1% EMPTY  pkg 0402LF  page 279 : 1 = PVCCD_HV_CPU0_LSET1 ; 2 = GND
PR3002  Q_RES  0 5% CHIP  pkg 0402LF  page 301 : 1 = GND ; 2 = AGND_HSC
PR3335  Q_RES  30.1K 1% CHIP  pkg 0402LF  page 281 : 1 = PVPP_HBM_CPU0_MODE ; 2 = GND
PR3336  Q_RES  30.1K 1% CHIP  pkg 0402LF  page 299 : 1 = PVPP_HBM_CPU1_MODE ; 2 = GND
PR3337  Q_RES  0 5% CHIP  pkg 0402LF  page 258 : 1 = P5V_AUX_MODE ; 2 = GND
PR3338  Q_RES  0 5% CHIP  pkg 0402LF  page 300 : 1 = P3V3_AUX ; 2 = PVNN_MAIN_CPU1_VCC
PR3339  Q_RES  0 5% CHIP  pkg 0402LF  page 282 : 1 = P3V3_AUX ; 2 = PVNN_MAIN_CPU0_VCC
PR3780  Q_RES  5.36K 1% CHIP  pkg 0402LF  page 156 : 1 = P3V3_OCP_CB_1 ; 2 = GND
PR3781  Q_RES  845 1% EMPTY  pkg 0402LF  page 156 : 1 = P12V_OCP_SENSE_1 ; 2 = GND
PR3782  Q_RES  10 1% CHIP  pkg 0402LF  page 162 : 1 = P3V3_AUX ; 2 = P3V3_OCP_VCC_2
PR3786  Q_RES  160K 1% EMPTY  pkg 0402LF  page 156 : 1 = P12V_AUX ; 2 = P12V_OCP_UV_1
PR3787  Q_RES  6.8K 1% EMPTY  pkg 0402LF  page 156 : 1 = P12V_OCP_UV_1 ; 2 = P12V_OCP_OV_1
PR3788  Q_RES  15K 1% EMPTY  pkg 0402LF  page 156 : 1 = P12V_OCP_OV_1 ; 2 = GND
PR3789  Q_RES  25.5K 1% CHIP  pkg 0402LF  page 156 : 1 = P3V3_AUX ; 2 = P3V3_OCP_UV_1
PR3790  Q_RES  7.15K 1% CHIP  pkg 0402LF  page 156 : 1 = P3V3_OCP_UV_1 ; 2 = P3V3_OCP_OV_1
PR3791  Q_RES  15K 1% CHIP  pkg 0402LF  page 156 : 1 = P3V3_OCP_OV_1 ; 2 = GND
PR3792  Q_RES  10 1% EMPTY  pkg 0402LF  page 156 : 1 = P12V_AUX ; 2 = P12V_OCP_VCC_1
PR3795  Q_RES  25.5K 1% CHIP  pkg 0402LF  page 162 : 1 = P3V3_AUX ; 2 = P3V3_OCP_UV_2
PR3798  Q_RES  10 1% CHIP  pkg 0402LF  page 156 : 1 = P3V3_AUX ; 2 = P3V3_OCP_VCC_1
PR3805  Q_RES  160K 1% EMPTY  pkg 0402LF  page 162 : 1 = P12V_AUX ; 2 = P12V_OCP_UV_2
PR3806  Q_RES  6.8K 1% EMPTY  pkg 0402LF  page 162 : 1 = P12V_OCP_UV_2 ; 2 = P12V_OCP_OV_2
PR3812  Q_RES  15K 1% CHIP  pkg 0402LF  page 162 : 1 = P3V3_OCP_OV_2 ; 2 = GND
PR3821  Q_RES  30.1K 1% EMPTY  pkg 0402LF  page 162 : 1 = P12V_OCP_CB_2 ; 2 = GND
PR3822  Q_RES  5.36K 1% CHIP  pkg 0402LF  page 162 : 1 = P3V3_OCP_CB_2 ; 2 = GND
PR3823  Q_RES  845 1% EMPTY  pkg 0402LF  page 162 : 1 = P12V_OCP_SENSE_2 ; 2 = GND
PR3824  Q_RES  4.53K 1% CHIP  pkg 0402LF  page 162 : 1 = P3V3_OCP_SENSE_2 ; 2 = GND
PR3828  Q_RES  15K 1% EMPTY  pkg 0402LF  page 162 : 1 = P12V_OCP_OV_2 ; 2 = GND
PR3829  Q_RES  7.15K 1% CHIP  pkg 0402LF  page 162 : 1 = P3V3_OCP_UV_2 ; 2 = P3V3_OCP_OV_2
PR3830  Q_RES  10 1% EMPTY  pkg 0402LF  page 162 : 1 = P12V_AUX ; 2 = P12V_OCP_VCC_2
PR3835  Q_RES  14.3K 1% CHIP  pkg 0402LF  page 157 : 1 = P12V_OCP_ISET_1 ; 2 = GND
PR3837  Q_RES  17.4K 1% CHIP  pkg 0402LF  page 157 : 1 = P12V_OCP_IMON_1 ; 2 = GND
PR3838  Q_RES  100 1% EMPTY  pkg 0402LF  page 157 : 1 = P12V_OCP_SFF ; 2 = P12V_OCP_AVIN_PD_1
PR3839  Q_RES  10K 1% CHIP  pkg 0402LF  page 157 : 1 = P12V_OCP_FLTB_1 ; 2 = P3V3_AUX
PR3840  Q_RES  71.5K 1% EMPTY  pkg 0402LF  page 157 : 1 = P12V_OCP_SFF ; 2 = P12V_OCP_OV_FB_1
PR3841  Q_RES  120K 1% CHIP  pkg 0402LF  page 157 : 1 = P12V_AUX ; 2 = P12V_OCP_OV_FB_1
PR3842  Q_RES  10K 1% CHIP  pkg 0402LF  page 157 : 1 = P12V_OCP_OV_FB_1 ; 2 = GND
PR3843  Q_RES  49.9 1% CHIP  pkg 0603LF  page 157 : 1 = P12V_AUX ; 2 = P12V_OCP_AVIN_PD_1
PR3844  Q_RES  71.5K 1% EMPTY  pkg 0402LF  page 157 : 1 = P3V3_OCP_MODE_1 ; 2 = GND
PR3846  Q_RES  1.33K 1% EMPTY  pkg 0402LF  page 157 : 1 = GND ; 2 = P3V3_OCP_ILIMIT_1
PR3847  Q_RES  14.3K 1% CHIP  pkg 0402LF  page 163 : 1 = P12V_OCP_ISET_2 ; 2 = GND
PR3849  Q_RES  17.4K 1% CHIP  pkg 0402LF  page 163 : 1 = P12V_OCP_IMON_2 ; 2 = GND
PR3850  Q_RES  100 1% EMPTY  pkg 0402LF  page 163 : 1 = P12V_OCP_V3_2 ; 2 = P12V_OCP_AVIN_PD_2
PR3851  Q_RES  10K 1% CHIP  pkg 0402LF  page 163 : 1 = P12V_OCP_FLTB_2 ; 2 = P3V3_AUX
